# BASEBOARD_FAB2 (Tioga Pass) — schematic netlist excerpt (pin names and nets, part order shuffled) for the footprints in the layout excerpt that follows; sources: Cadence DE-HDL packaged netlist, KiCad conversion of Wiwynn_Tioga_Pass_MB.brd

C9F2  SC22U16V5MX-4-GP  20%  pkg SMD-BCG5  page 139 : \1\ = P3V3_STBY ; \2\ = GND
R4T8  RES  665 1.0% CHIP  pkg 0402  page 99 : A = PVPP_ABC ; B = SMB_DDR_ABC_VPP_SDA_R
RN8F2  RES  4.75K 1% EMPTY  pkg 0402  page 246 : A = P3V3_STBY ; B = TPM_SPI_BMC_WP_N

(kicad_pcb
	(version 20260206)
	(generator "pcbnew")
	(generator_version "10.0")
	(general
		(thickness 1.6)
		(legacy_teardrops no)
	)
	(paper "A4")
	(title_block
		(title "Wiwynn_Tioga_Pass_MB.brd")
		(comment 1 "Tioga Pass / footprints 3655-3657 of 4770")
	)
	(layers
		(0 "F.Cu" signal "TOP")
		(4 "In1.Cu" signal "L2GND")
		(6 "In2.Cu" signal "L3")
		(8 "In3.Cu" signal "L4GND")
		(10 "In4.Cu" signal "L5")
		(12 "In5.Cu" signal "L6GND")
		(14 "In6.Cu" signal "L7VCC")
		(16 "In7.Cu" signal "L8VCC")
		(18 "In8.Cu" signal "L9GND")
		(20 "In9.Cu" signal "L10")
		(22 "In10.Cu" signal "L11GND")
		(24 "In11.Cu" signal "L12")
		(26 "In12.Cu" signal "L13GND")
		(2 "B.Cu" signal "BOTTOM")
		(9 "F.Adhes" user "F.Adhesive")
		(11 "B.Adhes" user "B.Adhesive")
		(13 "F.Paste" user "Package Geometry/Pastemask Top")
		(15 "B.Paste" user "Package Geometry/Pastemask Bottom")
		(5 "F.SilkS" user "Ref Des/Silkscreen Top")
		(7 "B.SilkS" user "Ref Des/Silkscreen Bottom")
		(1 "F.Mask" user "Board Geometry/Soldermask Top")
		(3 "B.Mask" user "Board Geometry/Soldermask Bottom")
		(17 "Dwgs.User" user "User.Drawings")
		(19 "Cmts.User" user "User.Comments")
		(21 "Eco1.User" user "User.Eco1")
		(23 "Eco2.User" user "User.Eco2")
		(25 "Edge.Cuts" user "Board Geometry/Outline")
		(27 "Margin" user)
		(31 "F.CrtYd" user "Package Geometry/Place Bound Top")
		(29 "B.CrtYd" user "Package Geometry/Place Bound Bottom")
		(35 "F.Fab" user "Ref Des/Assembly Top")
		(33 "B.Fab" user "Ref Des/Assembly Bottom")
	)
	(footprint ""
		(layer "B.Cu")
		(at 321.1957 -28.36418 90)
		(property "Reference" "R4T8"
			(at 0 0 90)
			(layer "B.SilkS")
			(hide yes)
			(effects
				(font
					(size 1.27 1.27)
				)
				(justify mirror)
			)
		)
		(property "Value" ""
			(at 0 0 90)
			(layer "B.Fab")
			(effects
				(font
					(size 1.27 1.27)
				)
				(justify mirror)
			)
		)
		(duplicate_pad_numbers_are_jumpers no)
		(fp_poly
			(pts
				(xy 0.2794 -0.1016) (xy -0.2794 -0.1016) (xy -0.2794 0.9906) (xy 0.2794 0.9906)
			)
			(stroke
				(width 0)
				(type default)
			)
			(fill no)
			(layer "B.CrtYd")
		)
		(fp_line
			(start 0.2794 -0.1016)
			(end 0.2794 0.9906)
			(stroke
				(width 0.1)
				(type default)
			)
			(layer "B.Fab")
		)
		(fp_line
			(start -0.2794 -0.1016)
			(end 0.2794 -0.1016)
			(stroke
				(width 0.1)
				(type default)
			)
			(layer "B.Fab")
		)
		(fp_line
			(start 0.2794 0.9906)
			(end -0.2794 0.9906)
			(stroke
				(width 0.1)
				(type default)
			)
			(layer "B.Fab")
		)
		(fp_line
			(start -0.2794 0.9906)
			(end -0.2794 -0.1016)
			(stroke
				(width 0.1)
				(type default)
			)
			(layer "B.Fab")
		)
		(pad "1" smd rect
			(at 0 0 270)
			(size 0.508 0.508)
			(layers "B.Cu" "B.Mask" "B.Paste")
			(net "PVPP_ABC")
		)
		(pad "2" smd rect
			(at 0 0.889 270)
			(size 0.508 0.508)
			(layers "B.Cu" "B.Mask" "B.Paste")
			(net "SMB_DDR_ABC_VPP_SDA_R")
		)
		(zone
			(layer "B.Cu")
			(hatch none 0.5)
			(connect_pads
				(clearance 0)
			)
			(min_thickness 0.25)
			(keepout
				(tracks allowed)
				(vias not_allowed)
				(pads allowed)
				(copperpour not_allowed)
				(footprints allowed)
			)
			(placement
				(enabled no)
				(sheetname "")
			)
			(fill
				(thermal_gap 0.5)
				(thermal_bridge_width 0.5)
				(island_removal_mode 0)
			)
			(polygon
				(pts
					(xy 321.4497 -28.61818) (xy 321.4497 -28.11018) (xy 321.8307 -28.11018) (xy 321.8307 -28.61818)
				)
			)
		)
		(zone
			(layer "B.Cu")
			(hatch none 0.5)
			(connect_pads
				(clearance 0)
			)
			(min_thickness 0.25)
			(keepout
				(tracks not_allowed)
				(vias allowed)
				(pads allowed)
				(copperpour not_allowed)
				(footprints allowed)
			)
			(placement
				(enabled no)
				(sheetname "")
			)
			(fill
				(thermal_gap 0.5)
				(thermal_bridge_width 0.5)
				(island_removal_mode 0)
			)
			(polygon
				(pts
					(xy 321.8307 -28.61818) (xy 321.8307 -28.11018) (xy 321.4497 -28.11018) (xy 321.4497 -28.61818)
				)
			)
		)
	)
	(footprint ""
		(layer "B.Cu")
		(at 370.078 -28.448)
		(property "Reference" "RN8F2"
			(at 0.8382 -0.67818 0)
			(unlocked yes)
			(layer "B.SilkS")
			(effects
				(font
					(size 0.4064 0.254)
					(thickness 0.1524)
				)
				(justify left mirror)
			)
		)
		(property "Value" ""
			(at 0 0 0)
			(layer "B.Fab")
			(effects
				(font
					(size 1.27 1.27)
				)
				(justify mirror)
			)
		)
		(duplicate_pad_numbers_are_jumpers no)
		(fp_poly
			(pts
				(xy 0.2794 -0.1016) (xy -0.2794 -0.1016) (xy -0.2794 0.9906) (xy 0.2794 0.9906)
			)
			(stroke
				(width 0)
				(type default)
			)
			(fill no)
			(layer "B.CrtYd")
		)
		(fp_line
			(start -0.2794 -0.1016)
			(end 0.2794 -0.1016)
			(stroke
				(width 0.1)
				(type default)
			)
			(layer "B.Fab")
		)
		(fp_line
			(start -0.2794 0.9906)
			(end -0.2794 -0.1016)
			(stroke
				(width 0.1)
				(type default)
			)
			(layer "B.Fab")
		)
		(fp_line
			(start 0.2794 -0.1016)
			(end 0.2794 0.9906)
			(stroke
				(width 0.1)
				(type default)
			)
			(layer "B.Fab")
		)
		(fp_line
			(start 0.2794 0.9906)
			(end -0.2794 0.9906)
			(stroke
				(width 0.1)
				(type default)
			)
			(layer "B.Fab")
		)
		(pad "1" smd rect
			(at 0 0 180)
			(size 0.508 0.508)
			(layers "B.Cu" "B.Mask" "B.Paste")
			(net "P3V3_STBY")
		)
		(pad "2" smd rect
			(at 0 0.889 180)
			(size 0.508 0.508)
			(layers "B.Cu" "B.Mask" "B.Paste")
			(net "TPM_SPI_BMC_WP_N")
		)
		(zone
			(layer "B.Cu")
			(hatch none 0.5)
			(connect_pads
				(clearance 0)
			)
			(min_thickness 0.25)
			(keepout
				(tracks allowed)
				(vias not_allowed)
				(pads allowed)
				(copperpour not_allowed)
				(footprints allowed)
			)
			(placement
				(enabled no)
				(sheetname "")
			)
			(fill
				(thermal_gap 0.5)
				(thermal_bridge_width 0.5)
				(island_removal_mode 0)
			)
			(polygon
				(pts
					(xy 370.332 -28.194) (xy 369.824 -28.194) (xy 369.824 -27.813) (xy 370.332 -27.813)
				)
			)
		)
		(zone
			(layer "B.Cu")
			(hatch none 0.5)
			(connect_pads
				(clearance 0)
			)
			(min_thickness 0.25)
			(keepout
				(tracks not_allowed)
				(vias allowed)
				(pads allowed)
				(copperpour not_allowed)
				(footprints allowed)
			)
			(placement
				(enabled no)
				(sheetname "")
			)
			(fill
				(thermal_gap 0.5)
				(thermal_bridge_width 0.5)
				(island_removal_mode 0)
			)
			(polygon
				(pts
					(xy 370.332 -27.813) (xy 369.824 -27.813) (xy 369.824 -28.194) (xy 370.332 -28.194)
				)
			)
		)
	)
	(footprint ""
		(layer "B.Cu")
		(at 476.1992 -48.5394 -90)
		(property "Reference" "C9F2"
			(at 0 0 90)
			(layer "B.SilkS")
			(hide yes)
			(effects
				(font
					(size 1.27 1.27)
				)
				(justify mirror)
			)
		)
		(property "Value" "*"
			(at 0.0762 -6.2357 270)
			(unlocked yes)
			(layer "B.Fab")
			(hide yes)
			(effects
				(font
					(size 1.27 1.016)
					(thickness 0.1524)
				)
				(justify mirror)
			)
		)
		(property "Device Type" "SC22U16V5MX-4-GP_SMD-BCG5-SC22A"
			(at 0.0762 -8.2677 270)
			(unlocked yes)
			(layer "B.Fab")
			(hide yes)
			(effects
				(font
					(size 1.27 1.016)
					(thickness 0.1524)
				)
				(justify mirror)
			)
		)
		(duplicate_pad_numbers_are_jumpers no)
		(fp_line
			(start -0.635 0)
			(end 0.635 0)
			(stroke
				(width 0.508)
				(type default)
			)
			(layer "B.SilkS")
		)
		(fp_rect
			(start 0.9652 1.778)
			(end -0.9652 -1.778)
			(stroke
				(width 0)
				(type default)
			)
			(fill no)
			(layer "B.CrtYd")
		)
		(fp_poly
			(pts
				(xy 0.9652 -1.778) (xy -0.9652 -1.778) (xy -0.9652 1.778) (xy 0.9652 1.778)
			)
			(stroke
				(width 0)
				(type default)
			)
			(fill no)
			(layer "B.Fab")
		)
		(pad "1" smd rect
			(at 0 -0.9652 90)
			(size 1.397 1.143)
			(layers "B.Cu" "B.Mask" "B.Paste")
			(net "P3V3_STBY")
		)
		(pad "2" smd rect
			(at 0 0.9652 90)
			(size 1.397 1.143)
			(layers "B.Cu" "B.Mask" "B.Paste")
			(net "GND")
		)
	)
)
